(kicad_pcb
	(version 20260206)
	(generator "pcbnew")
	(generator_version "10.0")
	(general
		(thickness 1.6)
		(legacy_teardrops no)
	)
	(paper "A4")
	(title_block
		(title "Wiwynn_Tioga_Pass_MB.brd")
		(comment 1 "Tioga Pass / footprints 1135-1141 of 4770")
	)
	(layers
		(0 "F.Cu" signal "TOP")
		(4 "In1.Cu" signal "L2GND")
		(6 "In2.Cu" signal "L3")
		(8 "In3.Cu" signal "L4GND")
		(10 "In4.Cu" signal "L5")
		(12 "In5.Cu" signal "L6GND")
		(14 "In6.Cu" signal "L7VCC")
		(16 "In7.Cu" signal "L8VCC")
		(18 "In8.Cu" signal "L9GND")
		(20 "In9.Cu" signal "L10")
		(22 "In10.Cu" signal "L11GND")
		(24 "In11.Cu" signal "L12")
		(26 "In12.Cu" signal "L13GND")
		(2 "B.Cu" signal "BOTTOM")
		(9 "F.Adhes" user "F.Adhesive")
		(11 "B.Adhes" user "B.Adhesive")
		(13 "F.Paste" user "Package Geometry/Pastemask Top")
		(15 "B.Paste" user "Package Geometry/Pastemask Bottom")
		(5 "F.SilkS" user "Ref Des/Silkscreen Top")
		(7 "B.SilkS" user "Ref Des/Silkscreen Bottom")
		(1 "F.Mask" user "Board Geometry/Soldermask Top")
		(3 "B.Mask" user "Board Geometry/Soldermask Bottom")
		(17 "Dwgs.User" user "User.Drawings")
		(19 "Cmts.User" user "User.Comments")
		(21 "Eco1.User" user "User.Eco1")
		(23 "Eco2.User" user "User.Eco2")
		(25 "Edge.Cuts" user "Board Geometry/Outline")
		(27 "Margin" user)
		(31 "F.CrtYd" user "Package Geometry/Place Bound Top")
		(29 "B.CrtYd" user "Package Geometry/Place Bound Bottom")
		(35 "F.Fab" user "Ref Des/Assembly Top")
		(33 "B.Fab" user "Ref Des/Assembly Bottom")
	)
	(footprint ""
		(layer "F.Cu")
		(at 260.697472 -81.573116)
		(property "Reference" "C5D12"
			(at 0 0 0)
			(layer "F.SilkS")
			(hide yes)
			(effects
				(font
					(size 1.27 1.27)
				)
			)
		)
		(property "Value" ""
			(at 0 0 0)
			(layer "F.Fab")
			(effects
				(font
					(size 1.27 1.27)
				)
			)
		)
		(duplicate_pad_numbers_are_jumpers no)
		(fp_poly
			(pts
				(xy -0.4953 -0.2032) (xy 0.4953 -0.2032) (xy 0.4953 1.6002) (xy -0.4953 1.6002)
			)
			(stroke
				(width 0)
				(type default)
			)
			(fill no)
			(layer "F.CrtYd")
		)
		(fp_line
			(start -0.4953 -0.2032)
			(end 0.4953 -0.2032)
			(stroke
				(width 0.1)
				(type default)
			)
			(layer "F.Fab")
		)
		(fp_line
			(start -0.4953 1.6002)
			(end -0.4953 -0.2032)
			(stroke
				(width 0.1)
				(type default)
			)
			(layer "F.Fab")
		)
		(fp_line
			(start 0.4953 -0.2032)
			(end 0.4953 1.6002)
			(stroke
				(width 0.1)
				(type default)
			)
			(layer "F.Fab")
		)
		(fp_line
			(start 0.4953 1.6002)
			(end -0.4953 1.6002)
			(stroke
				(width 0.1)
				(type default)
			)
			(layer "F.Fab")
		)
		(pad "1" smd rect
			(at 0 0)
			(size 0.762 0.889)
			(layers "F.Cu" "F.Mask" "F.Paste")
			(net "PVSA_CPU0")
		)
		(pad "2" smd rect
			(at 0 1.397)
			(size 0.762 0.889)
			(layers "F.Cu" "F.Mask" "F.Paste")
			(net "GND")
		)
		(zone
			(layer "F.Cu")
			(hatch none 0.5)
			(connect_pads
				(clearance 0)
			)
			(min_thickness 0.25)
			(keepout
				(tracks not_allowed)
				(vias allowed)
				(pads allowed)
				(copperpour not_allowed)
				(footprints allowed)
			)
			(placement
				(enabled no)
				(sheetname "")
			)
			(fill
				(thermal_gap 0.5)
				(thermal_bridge_width 0.5)
				(island_removal_mode 0)
			)
			(polygon
				(pts
					(xy 260.316472 -81.128616) (xy 261.078472 -81.128616) (xy 261.078472 -80.620616) (xy 260.316472 -80.620616)
				)
			)
		)
	)
	(footprint ""
		(layer "F.Cu")
		(at 393.827 -87.3125 180)
		(property "Reference" "R8D14"
			(at 0 0 180)
			(layer "F.SilkS")
			(hide yes)
			(effects
				(font
					(size 1.27 1.27)
				)
			)
		)
		(property "Value" ""
			(at 0 0 180)
			(layer "F.Fab")
			(effects
				(font
					(size 1.27 1.27)
				)
			)
		)
		(duplicate_pad_numbers_are_jumpers no)
		(fp_poly
			(pts
				(xy -0.2794 -0.1016) (xy 0.2794 -0.1016) (xy 0.2794 0.9906) (xy -0.2794 0.9906)
			)
			(stroke
				(width 0)
				(type default)
			)
			(fill no)
			(layer "F.CrtYd")
		)
		(fp_line
			(start 0.2794 0.9906)
			(end 0.2794 -0.1016)
			(stroke
				(width 0.1)
				(type default)
			)
			(layer "F.Fab")
		)
		(fp_line
			(start 0.2794 -0.1016)
			(end -0.2794 -0.1016)
			(stroke
				(width 0.1)
				(type default)
			)
			(layer "F.Fab")
		)
		(fp_line
			(start -0.2794 0.9906)
			(end 0.2794 0.9906)
			(stroke
				(width 0.1)
				(type default)
			)
			(layer "F.Fab")
		)
		(fp_line
			(start -0.2794 -0.1016)
			(end -0.2794 0.9906)
			(stroke
				(width 0.1)
				(type default)
			)
			(layer "F.Fab")
		)
		(pad "1" smd rect
			(at 0 0 180)
			(size 0.508 0.508)
			(layers "F.Cu" "F.Mask" "F.Paste")
			(net "P3V3_STBY")
		)
		(pad "2" smd rect
			(at 0 0.889 180)
			(size 0.508 0.508)
			(layers "F.Cu" "F.Mask" "F.Paste")
			(net "FP_PWR_ID_LED_N")
		)
		(zone
			(layer "F.Cu")
			(hatch none 0.5)
			(connect_pads
				(clearance 0)
			)
			(min_thickness 0.25)
			(keepout
				(tracks not_allowed)
				(vias allowed)
				(pads allowed)
				(copperpour not_allowed)
				(footprints allowed)
			)
			(placement
				(enabled no)
				(sheetname "")
			)
			(fill
				(thermal_gap 0.5)
				(thermal_bridge_width 0.5)
				(island_removal_mode 0)
			)
			(polygon
				(pts
					(xy 394.081 -87.9475) (xy 393.573 -87.9475) (xy 393.573 -87.5665) (xy 394.081 -87.5665)
				)
			)
		)
		(zone
			(layer "F.Cu")
			(hatch none 0.5)
			(connect_pads
				(clearance 0)
			)
			(min_thickness 0.25)
			(keepout
				(tracks allowed)
				(vias not_allowed)
				(pads allowed)
				(copperpour not_allowed)
				(footprints allowed)
			)
			(placement
				(enabled no)
				(sheetname "")
			)
			(fill
				(thermal_gap 0.5)
				(thermal_bridge_width 0.5)
				(island_removal_mode 0)
			)
			(polygon
				(pts
					(xy 394.081 -87.5665) (xy 393.573 -87.5665) (xy 393.573 -87.9475) (xy 394.081 -87.9475)
				)
			)
		)
	)
	(footprint ""
		(layer "F.Cu")
		(at 388.366 -87.3125 180)
		(property "Reference" "R3P3"
			(at 0 0 180)
			(layer "F.SilkS")
			(hide yes)
			(effects
				(font
					(size 1.27 1.27)
				)
			)
		)
		(property "Value" ""
			(at 0 0 180)
			(layer "F.Fab")
			(effects
				(font
					(size 1.27 1.27)
				)
			)
		)
		(duplicate_pad_numbers_are_jumpers no)
		(fp_poly
			(pts
				(xy -0.2794 -0.1016) (xy 0.2794 -0.1016) (xy 0.2794 0.9906) (xy -0.2794 0.9906)
			)
			(stroke
				(width 0)
				(type default)
			)
			(fill no)
			(layer "F.CrtYd")
		)
		(fp_line
			(start 0.2794 0.9906)
			(end 0.2794 -0.1016)
			(stroke
				(width 0.1)
				(type default)
			)
			(layer "F.Fab")
		)
		(fp_line
			(start 0.2794 -0.1016)
			(end -0.2794 -0.1016)
			(stroke
				(width 0.1)
				(type default)
			)
			(layer "F.Fab")
		)
		(fp_line
			(start -0.2794 0.9906)
			(end 0.2794 0.9906)
			(stroke
				(width 0.1)
				(type default)
			)
			(layer "F.Fab")
		)
		(fp_line
			(start -0.2794 -0.1016)
			(end -0.2794 0.9906)
			(stroke
				(width 0.1)
				(type default)
			)
			(layer "F.Fab")
		)
		(pad "1" smd rect
			(at 0 0 180)
			(size 0.508 0.508)
			(layers "F.Cu" "F.Mask" "F.Paste")
			(net "RMII_SPRNGVLLE_BMC_PCH_RXD0")
		)
		(pad "2" smd rect
			(at 0 0.889 180)
			(size 0.508 0.508)
			(layers "F.Cu" "F.Mask" "F.Paste")
			(net "RMII_SPRNGVLLE_BMC_PCH_RXD0_R1")
		)
		(zone
			(layer "F.Cu")
			(hatch none 0.5)
			(connect_pads
				(clearance 0)
			)
			(min_thickness 0.25)
			(keepout
				(tracks not_allowed)
				(vias allowed)
				(pads allowed)
				(copperpour not_allowed)
				(footprints allowed)
			)
			(placement
				(enabled no)
				(sheetname "")
			)
			(fill
				(thermal_gap 0.5)
				(thermal_bridge_width 0.5)
				(island_removal_mode 0)
			)
			(polygon
				(pts
					(xy 388.62 -87.9475) (xy 388.112 -87.9475) (xy 388.112 -87.5665) (xy 388.62 -87.5665)
				)
			)
		)
		(zone
			(layer "F.Cu")
			(hatch none 0.5)
			(connect_pads
				(clearance 0)
			)
			(min_thickness 0.25)
			(keepout
				(tracks allowed)
				(vias not_allowed)
				(pads allowed)
				(copperpour not_allowed)
				(footprints allowed)
			)
			(placement
				(enabled no)
				(sheetname "")
			)
			(fill
				(thermal_gap 0.5)
				(thermal_bridge_width 0.5)
				(island_removal_mode 0)
			)
			(polygon
				(pts
					(xy 388.62 -87.5665) (xy 388.112 -87.5665) (xy 388.112 -87.9475) (xy 388.62 -87.9475)
				)
			)
		)
	)
	(footprint ""
		(layer "F.Cu")
		(at 401.955 -24.892)
		(property "Reference" "R25W151"
			(at -0.8382 -0.67818 0)
			(unlocked yes)
			(layer "F.SilkS")
			(effects
				(font
					(size 0.4064 0.254)
					(thickness 0.1524)
				)
				(justify left)
			)
		)
		(property "Value" ""
			(at 0 0 0)
			(layer "F.Fab")
			(effects
				(font
					(size 1.27 1.27)
				)
			)
		)
		(duplicate_pad_numbers_are_jumpers no)
		(fp_poly
			(pts
				(xy -0.2794 -0.1016) (xy 0.2794 -0.1016) (xy 0.2794 0.9906) (xy -0.2794 0.9906)
			)
			(stroke
				(width 0)
				(type default)
			)
			(fill no)
			(layer "F.CrtYd")
		)
		(fp_line
			(start -0.2794 -0.1016)
			(end -0.2794 0.9906)
			(stroke
				(width 0.1)
				(type default)
			)
			(layer "F.Fab")
		)
		(fp_line
			(start -0.2794 0.9906)
			(end 0.2794 0.9906)
			(stroke
				(width 0.1)
				(type default)
			)
			(layer "F.Fab")
		)
		(fp_line
			(start 0.2794 -0.1016)
			(end -0.2794 -0.1016)
			(stroke
				(width 0.1)
				(type default)
			)
			(layer "F.Fab")
		)
		(fp_line
			(start 0.2794 0.9906)
			(end 0.2794 -0.1016)
			(stroke
				(width 0.1)
				(type default)
			)
			(layer "F.Fab")
		)
		(pad "1" smd rect
			(at 0 0)
			(size 0.508 0.508)
			(layers "F.Cu" "F.Mask" "F.Paste")
			(net "GND")
		)
		(pad "2" smd rect
			(at 0 0.889)
			(size 0.508 0.508)
			(layers "F.Cu" "F.Mask" "F.Paste")
			(net "RMII_BMC_PCH_SPRNGVLLE_TXD1_R")
		)
		(zone
			(layer "F.Cu")
			(hatch none 0.5)
			(connect_pads
				(clearance 0)
			)
			(min_thickness 0.25)
			(keepout
				(tracks allowed)
				(vias not_allowed)
				(pads allowed)
				(copperpour not_allowed)
				(footprints allowed)
			)
			(placement
				(enabled no)
				(sheetname "")
			)
			(fill
				(thermal_gap 0.5)
				(thermal_bridge_width 0.5)
				(island_removal_mode 0)
			)
			(polygon
				(pts
					(xy 401.701 -24.638) (xy 402.209 -24.638) (xy 402.209 -24.257) (xy 401.701 -24.257)
				)
			)
		)
		(zone
			(layer "F.Cu")
			(hatch none 0.5)
			(connect_pads
				(clearance 0)
			)
			(min_thickness 0.25)
			(keepout
				(tracks not_allowed)
				(vias allowed)
				(pads allowed)
				(copperpour not_allowed)
				(footprints allowed)
			)
			(placement
				(enabled no)
				(sheetname "")
			)
			(fill
				(thermal_gap 0.5)
				(thermal_bridge_width 0.5)
				(island_removal_mode 0)
			)
			(polygon
				(pts
					(xy 401.701 -24.257) (xy 402.209 -24.257) (xy 402.209 -24.638) (xy 401.701 -24.638)
				)
			)
		)
	)
	(footprint ""
		(layer "F.Cu")
		(at 33.243012 -60.376308 90)
		(property "Reference" "C1E14"
			(at 0 0 90)
			(layer "F.SilkS")
			(hide yes)
			(effects
				(font
					(size 1.27 1.27)
				)
			)
		)
		(property "Value" ""
			(at 0 0 90)
			(layer "F.Fab")
			(effects
				(font
					(size 1.27 1.27)
				)
			)
		)
		(duplicate_pad_numbers_are_jumpers no)
		(fp_rect
			(start 0.3048 0.9906)
			(end -0.3048 -0.1016)
			(stroke
				(width 0)
				(type default)
			)
			(fill no)
			(layer "F.CrtYd")
		)
		(fp_line
			(start 0.3048 -0.1016)
			(end -0.3048 -0.1016)
			(stroke
				(width 0.1)
				(type default)
			)
			(layer "F.Fab")
		)
		(fp_line
			(start -0.3048 -0.1016)
			(end -0.3048 0.9906)
			(stroke
				(width 0.1)
				(type default)
			)
			(layer "F.Fab")
		)
		(fp_line
			(start 0.3048 0.9906)
			(end 0.3048 -0.1016)
			(stroke
				(width 0.1)
				(type default)
			)
			(layer "F.Fab")
		)
		(fp_line
			(start -0.3048 0.9906)
			(end 0.3048 0.9906)
			(stroke
				(width 0.1)
				(type default)
			)
			(layer "F.Fab")
		)
		(pad "1" smd rect
			(at 0 0 90)
			(size 0.508 0.508)
			(layers "F.Cu" "F.Mask" "F.Paste")
			(net "VR_FET_SW_P12V_STBY_PVCCIN_CPU1")
		)
		(pad "2" smd rect
			(at 0 0.889 90)
			(size 0.508 0.508)
			(layers "F.Cu" "F.Mask" "F.Paste")
			(net "GND")
		)
		(zone
			(layer "F.Cu")
			(hatch none 0.5)
			(connect_pads
				(clearance 0)
			)
			(min_thickness 0.25)
			(keepout
				(tracks not_allowed)
				(vias allowed)
				(pads allowed)
				(copperpour not_allowed)
				(footprints allowed)
			)
			(placement
				(enabled no)
				(sheetname "")
			)
			(fill
				(thermal_gap 0.5)
				(thermal_bridge_width 0.5)
				(island_removal_mode 0)
			)
			(polygon
				(pts
					(xy 33.878012 -60.630308) (xy 33.497012 -60.630308) (xy 33.497012 -60.122308) (xy 33.878012 -60.122308)
				)
			)
		)
		(zone
			(layer "F.Cu")
			(hatch none 0.5)
			(connect_pads
				(clearance 0)
			)
			(min_thickness 0.25)
			(keepout
				(tracks allowed)
				(vias not_allowed)
				(pads allowed)
				(copperpour not_allowed)
				(footprints allowed)
			)
			(placement
				(enabled no)
				(sheetname "")
			)
			(fill
				(thermal_gap 0.5)
				(thermal_bridge_width 0.5)
				(island_removal_mode 0)
			)
			(polygon
				(pts
					(xy 33.878012 -60.630308) (xy 33.497012 -60.630308) (xy 33.497012 -60.122308) (xy 33.878012 -60.122308)
				)
			)
		)
	)
	(footprint ""
		(layer "F.Cu")
		(at 447.548 -20.2565)
		(property "Reference" "R1W9"
			(at -0.8382 -0.67818 0)
			(unlocked yes)
			(layer "F.SilkS")
			(effects
				(font
					(size 0.4064 0.254)
					(thickness 0.1524)
				)
				(justify left)
			)
		)
		(property "Value" ""
			(at 0 0 0)
			(layer "F.Fab")
			(effects
				(font
					(size 1.27 1.27)
				)
			)
		)
		(duplicate_pad_numbers_are_jumpers no)
		(fp_poly
			(pts
				(xy -0.2794 -0.1016) (xy 0.2794 -0.1016) (xy 0.2794 0.9906) (xy -0.2794 0.9906)
			)
			(stroke
				(width 0)
				(type default)
			)
			(fill no)
			(layer "F.CrtYd")
		)
		(fp_line
			(start -0.2794 -0.1016)
			(end -0.2794 0.9906)
			(stroke
				(width 0.1)
				(type default)
			)
			(layer "F.Fab")
		)
		(fp_line
			(start -0.2794 0.9906)
			(end 0.2794 0.9906)
			(stroke
				(width 0.1)
				(type default)
			)
			(layer "F.Fab")
		)
		(fp_line
			(start 0.2794 -0.1016)
			(end -0.2794 -0.1016)
			(stroke
				(width 0.1)
				(type default)
			)
			(layer "F.Fab")
		)
		(fp_line
			(start 0.2794 0.9906)
			(end 0.2794 -0.1016)
			(stroke
				(width 0.1)
				(type default)
			)
			(layer "F.Fab")
		)
		(pad "1" smd rect
			(at 0 0)
			(size 0.508 0.508)
			(layers "F.Cu" "F.Mask" "F.Paste")
			(net "PWRGD_P2V5_BMC_STBY_R")
		)
		(pad "2" smd rect
			(at 0 0.889)
			(size 0.508 0.508)
			(layers "F.Cu" "F.Mask" "F.Paste")
			(net "PWRGD_P2V5_BMC_STBY")
		)
		(zone
			(layer "F.Cu")
			(hatch none 0.5)
			(connect_pads
				(clearance 0)
			)
			(min_thickness 0.25)
			(keepout
				(tracks allowed)
				(vias not_allowed)
				(pads allowed)
				(copperpour not_allowed)
				(footprints allowed)
			)
			(placement
				(enabled no)
				(sheetname "")
			)
			(fill
				(thermal_gap 0.5)
				(thermal_bridge_width 0.5)
				(island_removal_mode 0)
			)
			(polygon
				(pts
					(xy 447.294 -20.0025) (xy 447.802 -20.0025) (xy 447.802 -19.6215) (xy 447.294 -19.6215)
				)
			)
		)
		(zone
			(layer "F.Cu")
			(hatch none 0.5)
			(connect_pads
				(clearance 0)
			)
			(min_thickness 0.25)
			(keepout
				(tracks not_allowed)
				(vias allowed)
				(pads allowed)
				(copperpour not_allowed)
				(footprints allowed)
			)
			(placement
				(enabled no)
				(sheetname "")
			)
			(fill
				(thermal_gap 0.5)
				(thermal_bridge_width 0.5)
				(island_removal_mode 0)
			)
			(polygon
				(pts
					(xy 447.294 -19.6215) (xy 447.802 -19.6215) (xy 447.802 -20.0025) (xy 447.294 -20.0025)
				)
			)
		)
	)
	(footprint ""
		(layer "F.Cu")
		(at 7.33298 -128.36779)
		(property "Reference" "R12W20"
			(at 0 0 0)
			(layer "F.SilkS")
			(hide yes)
			(effects
				(font
					(size 1.27 1.27)
				)
			)
		)
		(property "Value" "*"
			(at 0.064008 -4.108196 0)
			(unlocked yes)
			(layer "F.Fab")
			(hide yes)
			(effects
				(font
					(size 1.27 1.016)
					(thickness 0.1524)
				)
			)
		)
		(property "Device Type" "665KR2B-GP_SMD-RG2-665KR2B-GP,A"
			(at 0.064008 -5.632196 0)
			(unlocked yes)
			(layer "F.Fab")
			(hide yes)
			(effects
				(font
					(size 1.27 1.016)
					(thickness 0.1524)
				)
			)
		)
		(duplicate_pad_numbers_are_jumpers no)
		(fp_line
			(start -0.508 -0.9398)
			(end -0.508 0.9398)
			(stroke
				(width 0.1524)
				(type default)
			)
			(layer "F.SilkS")
		)
		(fp_line
			(start 0.508 -0.9398)
			(end -0.508 -0.9398)
			(stroke
				(width 0.1524)
				(type default)
			)
			(layer "F.SilkS")
		)
		(fp_rect
			(start -0.508 0.9398)
			(end 0.508 -0.9398)
			(stroke
				(width 0)
				(type default)
			)
			(fill no)
			(layer "F.CrtYd")
		)
		(fp_rect
			(start -0.508 0.9398)
			(end 0.508 -0.9398)
			(stroke
				(width 0)
				(type default)
			)
			(fill no)
			(layer "F.Fab")
		)
		(pad "1" smd custom
			(at 0 -0.4445)
			(size 0.1397 0.1397)
			(layers "F.Cu" "F.Mask" "F.Paste")
			(net "VR_PVDDQ_KLM_AIINSEN")
			(options
				(clearance outline)
				(anchor circle)
			)
			(primitives
				(gr_poly
					(pts
						(arc
							(start -0.1778 -0.2794)
							(mid -0.249642 -0.249642)
							(end -0.2794 -0.1778)
						)
						(arc
							(start -0.2794 0.1778)
							(mid -0.249642 0.249642)
							(end -0.1778 0.2794)
						)
						(arc
							(start 0.1778 0.2794)
							(mid 0.249642 0.249642)
							(end 0.2794 0.1778)
						)
						(arc
							(start 0.2794 -0.1778)
							(mid 0.249642 -0.249642)
							(end 0.1778 -0.2794)
						)
					)
					(width 0)
					(fill yes)
				)
			)
		)
		(pad "2" smd custom
			(at 0 0.4445)
			(size 0.1397 0.1397)
			(layers "F.Cu" "F.Mask" "F.Paste")
			(net "VR_PVDDQ_KLM_VINSEN")
			(options
				(clearance outline)
				(anchor circle)
			)
			(primitives
				(gr_poly
					(pts
						(arc
							(start -0.1778 -0.2794)
							(mid -0.249642 -0.249642)
							(end -0.2794 -0.1778)
						)
						(arc
							(start -0.2794 0.1778)
							(mid -0.249642 0.249642)
							(end -0.1778 0.2794)
						)
						(arc
							(start 0.1778 0.2794)
							(mid 0.249642 0.249642)
							(end 0.2794 0.1778)
						)
						(arc
							(start 0.2794 -0.1778)
							(mid 0.249642 -0.249642)
							(end 0.1778 -0.2794)
						)
					)
					(width 0)
					(fill yes)
				)
			)
		)
	)
)
